(kicad_pcb
	(version 20260206)
	(generator "pcbnew")
	(generator_version "10.0")
	(general
		(thickness 1.6)
		(legacy_teardrops no)
	)
	(paper "A4")
	(title_block
		(title "Bryce Canyon_F.DPB_16315-1-OCP.brd")
		(comment 1 "Bryce Canyon / footprints 2095-2103 of 2223")
	)
	(layers
		(0 "F.Cu" signal "TOP")
		(4 "In1.Cu" signal "L2GND")
		(6 "In2.Cu" signal "L3")
		(8 "In3.Cu" signal "L4GND")
		(10 "In4.Cu" signal "L5")
		(12 "In5.Cu" signal "L6VCC")
		(14 "In6.Cu" signal "L7VCC")
		(16 "In7.Cu" signal "L8")
		(18 "In8.Cu" signal "L9GND")
		(20 "In9.Cu" signal "L10")
		(22 "In10.Cu" signal "L11GND")
		(2 "B.Cu" signal "BOTTOM")
		(9 "F.Adhes" user "F.Adhesive")
		(11 "B.Adhes" user "B.Adhesive")
		(13 "F.Paste" user "Package Geometry/Pastemask Top")
		(15 "B.Paste" user "Package Geometry/Pastemask Bottom")
		(5 "F.SilkS" user "Ref Des/Silkscreen Top")
		(7 "B.SilkS" user "Ref Des/Silkscreen Bottom")
		(1 "F.Mask" user "Board Geometry/Soldermask Top")
		(3 "B.Mask" user "Board Geometry/Soldermask Bottom")
		(17 "Dwgs.User" user "User.Drawings")
		(19 "Cmts.User" user "User.Comments")
		(21 "Eco1.User" user "User.Eco1")
		(23 "Eco2.User" user "User.Eco2")
		(25 "Edge.Cuts" user "Board Geometry/Outline")
		(27 "Margin" user)
		(31 "F.CrtYd" user "Package Geometry/Place Bound Top")
		(29 "B.CrtYd" user "Package Geometry/Place Bound Bottom")
		(35 "F.Fab" user "Ref Des/Assembly Top")
		(33 "B.Fab" user "Ref Des/Assembly Bottom")
	)
	(footprint ""
		(layer "B.Cu")
		(at 178.252628 -235.229908 180)
		(property "Reference" "R1290"
			(at 0 0 0)
			(layer "B.SilkS")
			(hide yes)
			(effects
				(font
					(size 1.27 1.27)
				)
				(justify mirror)
			)
		)
		(property "Value" "3D01R5F-GP"
			(at 0 -8.9535 180)
			(unlocked yes)
			(layer "B.Fab")
			(hide yes)
			(effects
				(font
					(size 1.27 1.016)
					(thickness 0.1524)
				)
				(justify mirror)
			)
		)
		(property "Device Type" "R805H24"
			(at 0 -10.6299 180)
			(unlocked yes)
			(layer "B.Fab")
			(hide yes)
			(effects
				(font
					(size 1.27 1.016)
					(thickness 0.1524)
				)
				(justify mirror)
			)
		)
		(duplicate_pad_numbers_are_jumpers no)
		(fp_line
			(start 0.889 1.7018)
			(end -0.889 1.7018)
			(stroke
				(width 0.1524)
				(type default)
			)
			(layer "B.SilkS")
		)
		(fp_line
			(start 0.889 0.0762)
			(end 0.889 1.7018)
			(stroke
				(width 0.1524)
				(type default)
			)
			(layer "B.SilkS")
		)
		(fp_line
			(start 0.889 -1.7018)
			(end 0.889 0.2794)
			(stroke
				(width 0.1524)
				(type default)
			)
			(layer "B.SilkS")
		)
		(fp_line
			(start -0.889 1.7018)
			(end -0.889 -0.508)
			(stroke
				(width 0.1524)
				(type default)
			)
			(layer "B.SilkS")
		)
		(fp_line
			(start -0.889 -1.7018)
			(end 0.889 -1.7018)
			(stroke
				(width 0.1524)
				(type default)
			)
			(layer "B.SilkS")
		)
		(fp_line
			(start -0.889 -1.7018)
			(end -0.889 -0.381)
			(stroke
				(width 0.1524)
				(type default)
			)
			(layer "B.SilkS")
		)
		(fp_poly
			(pts
				(xy -0.9652 -1.778) (xy -0.9652 1.778) (xy 0.9652 1.778) (xy 0.9652 -1.778)
			)
			(stroke
				(width 0)
				(type default)
			)
			(fill no)
			(layer "B.CrtYd")
		)
		(fp_rect
			(start 0.9652 1.778)
			(end -0.9652 -1.778)
			(stroke
				(width 0)
				(type default)
			)
			(fill no)
			(layer "B.Fab")
		)
		(pad "1" smd rect
			(at 0 -0.9652)
			(size 1.397 1.143)
			(layers "B.Cu" "B.Mask" "B.Paste")
			(net "P3V3_STBY_SNB")
		)
		(pad "2" smd rect
			(at 0 0.9652)
			(size 1.397 1.143)
			(layers "B.Cu" "B.Mask" "B.Paste")
			(net "GND")
		)
	)
	(footprint ""
		(layer "B.Cu")
		(at 194.162172 -228.396292 180)
		(property "Reference" "C671"
			(at 0 0 0)
			(layer "B.SilkS")
			(hide yes)
			(effects
				(font
					(size 1.27 1.27)
				)
				(justify mirror)
			)
		)
		(property "Value" "SC10U16V5KX-7-GP-U"
			(at 0.0762 -6.1214 180)
			(unlocked yes)
			(layer "B.Fab")
			(hide yes)
			(effects
				(font
					(size 1.016 1.016)
					(thickness 0.1524)
				)
				(justify mirror)
			)
		)
		(property "Device Type" "C805H58"
			(at 0.0762 -8.1534 180)
			(unlocked yes)
			(layer "B.Fab")
			(hide yes)
			(effects
				(font
					(size 1.016 1.016)
					(thickness 0.1524)
				)
				(justify mirror)
			)
		)
		(duplicate_pad_numbers_are_jumpers no)
		(fp_line
			(start -0.635 0)
			(end 0.635 0)
			(stroke
				(width 0.508)
				(type default)
			)
			(layer "B.SilkS")
		)
		(fp_rect
			(start 0.9652 1.778)
			(end -0.9652 -1.778)
			(stroke
				(width 0)
				(type default)
			)
			(fill no)
			(layer "B.CrtYd")
		)
		(fp_poly
			(pts
				(xy 0.9652 -1.778) (xy -0.9652 -1.778) (xy -0.9652 1.778) (xy 0.9652 1.778)
			)
			(stroke
				(width 0)
				(type default)
			)
			(fill no)
			(layer "B.Fab")
		)
		(pad "1" smd rect
			(at 0 -0.9652)
			(size 1.397 1.143)
			(layers "B.Cu" "B.Mask" "B.Paste")
			(net "P3V3_STBY_VIN")
		)
		(pad "2" smd rect
			(at 0 0.9652)
			(size 1.397 1.143)
			(layers "B.Cu" "B.Mask" "B.Paste")
			(net "GND")
		)
	)
	(footprint ""
		(layer "B.Cu")
		(at 216.8398 -116.459 90)
		(property "Reference" "R622"
			(at 0 0 90)
			(layer "B.SilkS")
			(hide yes)
			(effects
				(font
					(size 1.27 1.27)
				)
				(justify mirror)
			)
		)
		(property "Value" "4K7R2F-GP"
			(at -0.064008 -3.993896 90)
			(unlocked yes)
			(layer "B.Fab")
			(hide yes)
			(effects
				(font
					(size 1.016 1.016)
					(thickness 0.1524)
				)
				(justify mirror)
			)
		)
		(property "Device Type" "R402H16"
			(at -0.064008 -5.517896 90)
			(unlocked yes)
			(layer "B.Fab")
			(hide yes)
			(effects
				(font
					(size 1.016 1.016)
					(thickness 0.1524)
				)
				(justify mirror)
			)
		)
		(duplicate_pad_numbers_are_jumpers no)
		(fp_line
			(start 0.508 -0.9398)
			(end 0.508 0.9398)
			(stroke
				(width 0.1524)
				(type default)
			)
			(layer "B.SilkS")
		)
		(fp_line
			(start -0.508 -0.9398)
			(end 0.508 -0.9398)
			(stroke
				(width 0.1524)
				(type default)
			)
			(layer "B.SilkS")
		)
		(fp_rect
			(start 0.508 0.9398)
			(end -0.508 -0.9398)
			(stroke
				(width 0)
				(type default)
			)
			(fill no)
			(layer "B.CrtYd")
		)
		(fp_rect
			(start 0.508 0.9398)
			(end -0.508 -0.9398)
			(stroke
				(width 0)
				(type default)
			)
			(fill no)
			(layer "B.Fab")
		)
		(pad "1" smd custom
			(at 0 -0.4445 270)
			(size 0.1397 0.1397)
			(layers "B.Cu" "B.Mask" "B.Paste")
			(net "I2C_BMC_A_COMP_A_SDA")
			(options
				(clearance outline)
				(anchor circle)
			)
			(primitives
				(gr_poly
					(pts
						(arc
							(start -0.1778 0.2794)
							(mid -0.249642 0.249642)
							(end -0.2794 0.1778)
						)
						(arc
							(start -0.2794 -0.1778)
							(mid -0.249642 -0.249642)
							(end -0.1778 -0.2794)
						)
						(arc
							(start 0.1778 -0.2794)
							(mid 0.249642 -0.249642)
							(end 0.2794 -0.1778)
						)
						(arc
							(start 0.2794 0.1778)
							(mid 0.249642 0.249642)
							(end 0.1778 0.2794)
						)
					)
					(width 0)
					(fill yes)
				)
			)
		)
		(pad "2" smd custom
			(at 0 0.4445 270)
			(size 0.1397 0.1397)
			(layers "B.Cu" "B.Mask" "B.Paste")
			(net "P3V3_STBY_A")
			(options
				(clearance outline)
				(anchor circle)
			)
			(primitives
				(gr_poly
					(pts
						(arc
							(start -0.1778 0.2794)
							(mid -0.249642 0.249642)
							(end -0.2794 0.1778)
						)
						(arc
							(start -0.2794 -0.1778)
							(mid -0.249642 -0.249642)
							(end -0.1778 -0.2794)
						)
						(arc
							(start 0.1778 -0.2794)
							(mid 0.249642 -0.249642)
							(end 0.2794 -0.1778)
						)
						(arc
							(start 0.2794 0.1778)
							(mid 0.249642 0.249642)
							(end 0.1778 0.2794)
						)
					)
					(width 0)
					(fill yes)
				)
			)
		)
	)
	(footprint ""
		(layer "B.Cu")
		(at 47.356014 -148.695664 180)
		(property "Reference" "R1241"
			(at 0 0 0)
			(layer "B.SilkS")
			(hide yes)
			(effects
				(font
					(size 1.27 1.27)
				)
				(justify mirror)
			)
		)
		(property "Value" "10KR2F-2-GP"
			(at -0.064008 -3.993896 180)
			(unlocked yes)
			(layer "B.Fab")
			(hide yes)
			(effects
				(font
					(size 1.016 1.016)
					(thickness 0.1524)
				)
				(justify mirror)
			)
		)
		(property "Device Type" "R402H16"
			(at -0.064008 -5.517896 180)
			(unlocked yes)
			(layer "B.Fab")
			(hide yes)
			(effects
				(font
					(size 1.016 1.016)
					(thickness 0.1524)
				)
				(justify mirror)
			)
		)
		(duplicate_pad_numbers_are_jumpers no)
		(fp_line
			(start 0.508 -0.9398)
			(end 0.508 0.9398)
			(stroke
				(width 0.1524)
				(type default)
			)
			(layer "B.SilkS")
		)
		(fp_line
			(start -0.508 -0.9398)
			(end 0.508 -0.9398)
			(stroke
				(width 0.1524)
				(type default)
			)
			(layer "B.SilkS")
		)
		(fp_rect
			(start 0.508 0.9398)
			(end -0.508 -0.9398)
			(stroke
				(width 0)
				(type default)
			)
			(fill no)
			(layer "B.CrtYd")
		)
		(fp_rect
			(start 0.508 0.9398)
			(end -0.508 -0.9398)
			(stroke
				(width 0)
				(type default)
			)
			(fill no)
			(layer "B.Fab")
		)
		(pad "1" smd custom
			(at 0 -0.4445)
			(size 0.1397 0.1397)
			(layers "B.Cu" "B.Mask" "B.Paste")
			(net "P5V_B_VFB")
			(options
				(clearance outline)
				(anchor circle)
			)
			(primitives
				(gr_poly
					(pts
						(arc
							(start -0.1778 0.2794)
							(mid -0.249642 0.249642)
							(end -0.2794 0.1778)
						)
						(arc
							(start -0.2794 -0.1778)
							(mid -0.249642 -0.249642)
							(end -0.1778 -0.2794)
						)
						(arc
							(start 0.1778 -0.2794)
							(mid 0.249642 -0.249642)
							(end 0.2794 -0.1778)
						)
						(arc
							(start 0.2794 0.1778)
							(mid 0.249642 0.249642)
							(end 0.1778 0.2794)
						)
					)
					(width 0)
					(fill yes)
				)
			)
		)
		(pad "2" smd custom
			(at 0 0.4445)
			(size 0.1397 0.1397)
			(layers "B.Cu" "B.Mask" "B.Paste")
			(net "AGND_P5V_B")
			(options
				(clearance outline)
				(anchor circle)
			)
			(primitives
				(gr_poly
					(pts
						(arc
							(start -0.1778 0.2794)
							(mid -0.249642 0.249642)
							(end -0.2794 0.1778)
						)
						(arc
							(start -0.2794 -0.1778)
							(mid -0.249642 -0.249642)
							(end -0.1778 -0.2794)
						)
						(arc
							(start 0.1778 -0.2794)
							(mid 0.249642 -0.249642)
							(end 0.2794 -0.1778)
						)
						(arc
							(start 0.2794 0.1778)
							(mid 0.249642 0.249642)
							(end 0.1778 0.2794)
						)
					)
					(width 0)
					(fill yes)
				)
			)
		)
	)
	(footprint ""
		(layer "B.Cu")
		(at 436.732172 -252.076966 180)
		(property "Reference" "C635"
			(at 0 0 0)
			(layer "B.SilkS")
			(hide yes)
			(effects
				(font
					(size 1.27 1.27)
				)
				(justify mirror)
			)
		)
		(property "Value" "SC10U16V5KX-7-GP-U"
			(at 0.0762 -6.1214 180)
			(unlocked yes)
			(layer "B.Fab")
			(hide yes)
			(effects
				(font
					(size 1.016 1.016)
					(thickness 0.1524)
				)
				(justify mirror)
			)
		)
		(property "Device Type" "C805H58"
			(at 0.0762 -8.1534 180)
			(unlocked yes)
			(layer "B.Fab")
			(hide yes)
			(effects
				(font
					(size 1.016 1.016)
					(thickness 0.1524)
				)
				(justify mirror)
			)
		)
		(duplicate_pad_numbers_are_jumpers no)
		(fp_line
			(start -0.635 0)
			(end 0.635 0)
			(stroke
				(width 0.508)
				(type default)
			)
			(layer "B.SilkS")
		)
		(fp_rect
			(start 0.9652 1.778)
			(end -0.9652 -1.778)
			(stroke
				(width 0)
				(type default)
			)
			(fill no)
			(layer "B.CrtYd")
		)
		(fp_poly
			(pts
				(xy 0.9652 -1.778) (xy -0.9652 -1.778) (xy -0.9652 1.778) (xy 0.9652 1.778)
			)
			(stroke
				(width 0)
				(type default)
			)
			(fill no)
			(layer "B.Fab")
		)
		(pad "1" smd rect
			(at 0 -0.9652)
			(size 1.397 1.143)
			(layers "B.Cu" "B.Mask" "B.Paste")
			(net "P12V_A_VIN_U22")
		)
		(pad "2" smd rect
			(at 0 0.9652)
			(size 1.397 1.143)
			(layers "B.Cu" "B.Mask" "B.Paste")
			(net "GND")
		)
	)
	(footprint ""
		(layer "B.Cu")
		(at 432.501294 -255.739138 180)
		(property "Reference" "R1245"
			(at 0 0 0)
			(layer "B.SilkS")
			(hide yes)
			(effects
				(font
					(size 1.27 1.27)
				)
				(justify mirror)
			)
		)
		(property "Value" "2D2R3-1-U-GP"
			(at 0.0254 -2.5146 180)
			(unlocked yes)
			(layer "B.Fab")
			(hide yes)
			(effects
				(font
					(size 1.016 1.016)
					(thickness 0.1524)
				)
				(justify mirror)
			)
		)
		(property "Device Type" "R603H22"
			(at 0.0254 -4.0386 180)
			(unlocked yes)
			(layer "B.Fab")
			(hide yes)
			(effects
				(font
					(size 1.016 1.016)
					(thickness 0.1524)
				)
				(justify mirror)
			)
		)
		(duplicate_pad_numbers_are_jumpers no)
		(fp_line
			(start 0.4826 0)
			(end 0.2032 0)
			(stroke
				(width 0.2032)
				(type default)
			)
			(layer "B.SilkS")
		)
		(fp_line
			(start -0.2032 0)
			(end -0.4826 0)
			(stroke
				(width 0.2032)
				(type default)
			)
			(layer "B.SilkS")
		)
		(fp_rect
			(start 0.5842 1.3335)
			(end -0.5842 -1.3335)
			(stroke
				(width 0)
				(type default)
			)
			(fill no)
			(layer "B.CrtYd")
		)
		(fp_rect
			(start 0.5842 1.3335)
			(end -0.5842 -1.3335)
			(stroke
				(width 0)
				(type default)
			)
			(fill no)
			(layer "B.Fab")
		)
		(pad "1" smd custom
			(at 0 -0.762)
			(size 0.2159 0.2159)
			(layers "B.Cu" "B.Mask" "B.Paste")
			(net "P12V_A")
			(options
				(clearance outline)
				(anchor circle)
			)
			(primitives
				(gr_poly
					(pts
						(arc
							(start -0.3302 0.4318)
							(mid -0.402042 0.402042)
							(end -0.4318 0.3302)
						)
						(arc
							(start -0.4318 -0.3302)
							(mid -0.402042 -0.402042)
							(end -0.3302 -0.4318)
						)
						(arc
							(start 0.3302 -0.4318)
							(mid 0.402042 -0.402042)
							(end 0.4318 -0.3302)
						)
						(arc
							(start 0.4318 0.3302)
							(mid 0.402042 0.402042)
							(end 0.3302 0.4318)
						)
					)
					(width 0)
					(fill yes)
				)
			)
		)
		(pad "2" smd custom
			(at 0 0.762)
			(size 0.2159 0.2159)
			(layers "B.Cu" "B.Mask" "B.Paste")
			(net "P12V_A_VDD_U22")
			(options
				(clearance outline)
				(anchor circle)
			)
			(primitives
				(gr_poly
					(pts
						(arc
							(start -0.3302 0.4318)
							(mid -0.402042 0.402042)
							(end -0.4318 0.3302)
						)
						(arc
							(start -0.4318 -0.3302)
							(mid -0.402042 -0.402042)
							(end -0.3302 -0.4318)
						)
						(arc
							(start 0.3302 -0.4318)
							(mid 0.402042 -0.402042)
							(end 0.4318 -0.3302)
						)
						(arc
							(start 0.4318 0.3302)
							(mid 0.402042 0.402042)
							(end 0.3302 0.4318)
						)
					)
					(width 0)
					(fill yes)
				)
			)
		)
	)
	(footprint ""
		(layer "B.Cu")
		(at 472.186 -243.459 90)
		(property "Reference" "L7"
			(at 0 0 90)
			(layer "B.SilkS")
			(hide yes)
			(effects
				(font
					(size 1.27 1.27)
				)
				(justify mirror)
			)
		)
		(property "Value" "BLM21PG220SN1DGP"
			(at -0.0254 -5.6896 90)
			(unlocked yes)
			(layer "B.Fab")
			(hide yes)
			(effects
				(font
					(size 1.016 1.016)
					(thickness 0.1524)
				)
				(justify mirror)
			)
		)
		(property "Device Type" "L20125H42"
			(at -0.0254 -7.5946 90)
			(unlocked yes)
			(layer "B.Fab")
			(hide yes)
			(effects
				(font
					(size 1.016 1.016)
					(thickness 0.1524)
				)
				(justify mirror)
			)
		)
		(duplicate_pad_numbers_are_jumpers no)
		(fp_line
			(start 0.9144 -1.7018)
			(end 0.9144 1.7018)
			(stroke
				(width 0.1524)
				(type default)
			)
			(layer "B.SilkS")
		)
		(fp_line
			(start -0.9144 -1.7018)
			(end 0.9144 -1.7018)
			(stroke
				(width 0.1524)
				(type default)
			)
			(layer "B.SilkS")
		)
		(fp_line
			(start 0.9144 1.7018)
			(end -0.9144 1.7018)
			(stroke
				(width 0.1524)
				(type default)
			)
			(layer "B.SilkS")
		)
		(fp_line
			(start -0.9144 1.7018)
			(end -0.9144 -1.7018)
			(stroke
				(width 0.1524)
				(type default)
			)
			(layer "B.SilkS")
		)
		(fp_rect
			(start 1.0033 1.778)
			(end -1.0033 -1.778)
			(stroke
				(width 0)
				(type default)
			)
			(fill no)
			(layer "B.CrtYd")
		)
		(fp_poly
			(pts
				(xy 1.0033 -1.778) (xy -1.0033 -1.778) (xy -1.0033 1.778) (xy 1.0033 1.778)
			)
			(stroke
				(width 0)
				(type default)
			)
			(fill no)
			(layer "B.Fab")
		)
		(pad "1" smd rect
			(at 0 -0.9652 270)
			(size 1.397 1.143)
			(layers "B.Cu" "B.Mask" "B.Paste")
			(net "P12V_A")
		)
		(pad "2" smd rect
			(at 0 0.9652 270)
			(size 1.397 1.143)
			(layers "B.Cu" "B.Mask" "B.Paste")
			(net "P12V_A_VIN_U27")
		)
	)
	(footprint ""
		(layer "B.Cu")
		(at 471.17 -252.5522 180)
		(property "Reference" "C646"
			(at 0 0 0)
			(layer "B.SilkS")
			(hide yes)
			(effects
				(font
					(size 1.27 1.27)
				)
				(justify mirror)
			)
		)
		(property "Value" "SC10U16V5KX-7-GP-U"
			(at 0.0762 -6.1214 180)
			(unlocked yes)
			(layer "B.Fab")
			(hide yes)
			(effects
				(font
					(size 1.016 1.016)
					(thickness 0.1524)
				)
				(justify mirror)
			)
		)
		(property "Device Type" "C805H58"
			(at 0.0762 -8.1534 180)
			(unlocked yes)
			(layer "B.Fab")
			(hide yes)
			(effects
				(font
					(size 1.016 1.016)
					(thickness 0.1524)
				)
				(justify mirror)
			)
		)
		(duplicate_pad_numbers_are_jumpers no)
		(fp_line
			(start -0.635 0)
			(end 0.635 0)
			(stroke
				(width 0.508)
				(type default)
			)
			(layer "B.SilkS")
		)
		(fp_rect
			(start 0.9652 1.778)
			(end -0.9652 -1.778)
			(stroke
				(width 0)
				(type default)
			)
			(fill no)
			(layer "B.CrtYd")
		)
		(fp_poly
			(pts
				(xy 0.9652 -1.778) (xy -0.9652 -1.778) (xy -0.9652 1.778) (xy 0.9652 1.778)
			)
			(stroke
				(width 0)
				(type default)
			)
			(fill no)
			(layer "B.Fab")
		)
		(pad "1" smd rect
			(at 0 -0.9652)
			(size 1.397 1.143)
			(layers "B.Cu" "B.Mask" "B.Paste")
			(net "P5V_A_3")
		)
		(pad "2" smd rect
			(at 0 0.9652)
			(size 1.397 1.143)
			(layers "B.Cu" "B.Mask" "B.Paste")
			(net "GND")
		)
	)
	(footprint ""
		(layer "B.Cu")
		(at 480.695 -225.806 180)
		(property "Reference" "R1271"
			(at 0 0 0)
			(layer "B.SilkS")
			(hide yes)
			(effects
				(font
					(size 1.27 1.27)
				)
				(justify mirror)
			)
		)
		(property "Value" "15KR2F-GP"
			(at -0.064008 -3.993896 180)
			(unlocked yes)
			(layer "B.Fab")
			(hide yes)
			(effects
				(font
					(size 1.016 1.016)
					(thickness 0.1524)
				)
				(justify mirror)
			)
		)
		(property "Device Type" "R402H16"
			(at -0.064008 -5.517896 180)
			(unlocked yes)
			(layer "B.Fab")
			(hide yes)
			(effects
				(font
					(size 1.016 1.016)
					(thickness 0.1524)
				)
				(justify mirror)
			)
		)
		(duplicate_pad_numbers_are_jumpers no)
		(fp_line
			(start 0.508 -0.9398)
			(end 0.508 0.9398)
			(stroke
				(width 0.1524)
				(type default)
			)
			(layer "B.SilkS")
		)
		(fp_line
			(start -0.508 -0.9398)
			(end 0.508 -0.9398)
			(stroke
				(width 0.1524)
				(type default)
			)
			(layer "B.SilkS")
		)
		(fp_rect
			(start 0.508 0.9398)
			(end -0.508 -0.9398)
			(stroke
				(width 0)
				(type default)
			)
			(fill no)
			(layer "B.CrtYd")
		)
		(fp_rect
			(start 0.508 0.9398)
			(end -0.508 -0.9398)
			(stroke
				(width 0)
				(type default)
			)
			(fill no)
			(layer "B.Fab")
		)
		(pad "1" smd custom
			(at 0 -0.4445)
			(size 0.1397 0.1397)
			(layers "B.Cu" "B.Mask" "B.Paste")
			(net "P5V_A_4_PGOOD")
			(options
				(clearance outline)
				(anchor circle)
			)
			(primitives
				(gr_poly
					(pts
						(arc
							(start -0.1778 0.2794)
							(mid -0.249642 0.249642)
							(end -0.2794 0.1778)
						)
						(arc
							(start -0.2794 -0.1778)
							(mid -0.249642 -0.249642)
							(end -0.1778 -0.2794)
						)
						(arc
							(start 0.1778 -0.2794)
							(mid 0.249642 -0.249642)
							(end 0.2794 -0.1778)
						)
						(arc
							(start 0.2794 0.1778)
							(mid 0.249642 0.249642)
							(end 0.1778 0.2794)
						)
					)
					(width 0)
					(fill yes)
				)
			)
		)
		(pad "2" smd custom
			(at 0 0.4445)
			(size 0.1397 0.1397)
			(layers "B.Cu" "B.Mask" "B.Paste")
			(net "GND")
			(options
				(clearance outline)
				(anchor circle)
			)
			(primitives
				(gr_poly
					(pts
						(arc
							(start -0.1778 0.2794)
							(mid -0.249642 0.249642)
							(end -0.2794 0.1778)
						)
						(arc
							(start -0.2794 -0.1778)
							(mid -0.249642 -0.249642)
							(end -0.1778 -0.2794)
						)
						(arc
							(start 0.1778 -0.2794)
							(mid 0.249642 -0.249642)
							(end 0.2794 -0.1778)
						)
						(arc
							(start 0.2794 0.1778)
							(mid 0.249642 0.249642)
							(end 0.1778 0.2794)
						)
					)
					(width 0)
					(fill yes)
				)
			)
		)
	)
)
